(kicad_pcb
	(version 20260206)
	(generator "pcbnew")
	(generator_version "10.0")
	(general
		(thickness 1.6)
		(legacy_teardrops no)
	)
	(paper "A4")
	(title_block
		(title "timecard-production-celestica-r4006 — R4006-B0001-02_R01.brd")
		(comment 1 "Time Appliance Project (Time Card) / footprints 397-401 of 1113")
	)
	(layers
		(0 "F.Cu" signal "TOP")
		(4 "In1.Cu" signal "L02_GND1")
		(6 "In2.Cu" signal "L03_SIG1")
		(8 "In3.Cu" signal "L04_GND2")
		(10 "In4.Cu" signal "L05_VCC1")
		(12 "In5.Cu" signal "L06_VCC2")
		(14 "In6.Cu" signal "L07_GND3")
		(16 "In7.Cu" signal "L08_SIG2")
		(18 "In8.Cu" signal "L09_GND4")
		(2 "B.Cu" signal "BOTTOM")
		(9 "F.Adhes" user "F.Adhesive")
		(11 "B.Adhes" user "B.Adhesive")
		(13 "F.Paste" user "Package Geometry/Pastemask Top")
		(15 "B.Paste" user "Package Geometry/Pastemask Bottom")
		(5 "F.SilkS" user "Ref Des/Silkscreen Top")
		(7 "B.SilkS" user "Ref Des/Silkscreen Bottom")
		(1 "F.Mask" user "Board Geometry/Soldermask Top")
		(3 "B.Mask" user "Board Geometry/Soldermask Bottom")
		(17 "Dwgs.User" user "User.Drawings")
		(19 "Cmts.User" user "User.Comments")
		(21 "Eco1.User" user "User.Eco1")
		(23 "Eco2.User" user "User.Eco2")
		(25 "Edge.Cuts" user "Board Geometry/Outline")
		(27 "Margin" user)
		(31 "F.CrtYd" user "Package Geometry/Place Bound Top")
		(29 "B.CrtYd" user "Package Geometry/Place Bound Bottom")
		(35 "F.Fab" user "Ref Des/Assembly Top")
		(33 "B.Fab" user "Ref Des/Assembly Bottom")
	)
	(footprint ""
		(layer "F.Cu")
		(at 147.049998 -107.849924 -90)
		(property "Reference" "DS4"
			(at -0.862076 -1.706372 90)
			(unlocked yes)
			(layer "F.SilkS")
			(effects
				(font
					(size 0.7874 0.5842)
					(thickness 0.1524)
				)
			)
		)
		(property "Value" ""
			(at 0 0 270)
			(layer "F.Fab")
			(effects
				(font
					(size 1.27 1.27)
				)
			)
		)
		(property "User Part Number" "PARTNUM*"
			(at 0.1778 2.422881 270)
			(unlocked yes)
			(layer "Cmts.User")
			(hide yes)
			(effects
				(font
					(size 0.786892 0.583946)
					(thickness 0.000001)
				)
			)
		)
		(property "Device Type" "OPTICAL-G170-10143-01"
			(at 0.1778 1.483081 270)
			(unlocked yes)
			(layer "F.Fab")
			(hide yes)
			(effects
				(font
					(size 0.786892 0.583946)
					(thickness 0.000001)
				)
			)
		)
		(duplicate_pad_numbers_are_jumpers no)
		(fp_line
			(start -1.3208 1.0922)
			(end -2.5908 1.0922)
			(stroke
				(width 0.1)
				(type default)
			)
			(layer "F.SilkS")
		)
		(fp_line
			(start -1.397508 0.704088)
			(end -1.397508 -0.704088)
			(stroke
				(width 0.1)
				(type default)
			)
			(layer "F.SilkS")
		)
		(fp_line
			(start 1.397508 0.704088)
			(end -1.397508 0.704088)
			(stroke
				(width 0.1)
				(type default)
			)
			(layer "F.SilkS")
		)
		(fp_line
			(start -1.9558 0.4572)
			(end -1.9558 1.7272)
			(stroke
				(width 0.1)
				(type default)
			)
			(layer "F.SilkS")
		)
		(fp_line
			(start -1.397508 -0.704088)
			(end 1.397508 -0.704088)
			(stroke
				(width 0.1)
				(type default)
			)
			(layer "F.SilkS")
		)
		(fp_line
			(start 1.397508 -0.704088)
			(end 1.397508 0.704088)
			(stroke
				(width 0.1)
				(type default)
			)
			(layer "F.SilkS")
		)
		(fp_rect
			(start 1.905508 0.704088)
			(end 1.397508 -0.704088)
			(stroke
				(width 0)
				(type default)
			)
			(fill yes)
			(layer "F.SilkS")
		)
		(fp_rect
			(start 1.905508 0.958088)
			(end -1.651508 -0.958088)
			(stroke
				(width 0)
				(type default)
			)
			(fill no)
			(layer "F.CrtYd")
		)
		(fp_line
			(start -1.4478 0.9652)
			(end -2.7178 0.9652)
			(stroke
				(width 0.1)
				(type default)
			)
			(layer "F.Fab")
		)
		(fp_line
			(start -0.850138 0.450088)
			(end 0.850138 0.450088)
			(stroke
				(width 0.1)
				(type default)
			)
			(layer "F.Fab")
		)
		(fp_line
			(start 0.850138 0.450088)
			(end 0.850138 -0.450088)
			(stroke
				(width 0.1)
				(type default)
			)
			(layer "F.Fab")
		)
		(fp_line
			(start -2.0828 0.3302)
			(end -2.0828 1.6002)
			(stroke
				(width 0.1)
				(type default)
			)
			(layer "F.Fab")
		)
		(fp_line
			(start -0.850138 -0.450088)
			(end -0.850138 0.450088)
			(stroke
				(width 0.1)
				(type default)
			)
			(layer "F.Fab")
		)
		(fp_line
			(start 0.850138 -0.450088)
			(end -0.850138 -0.450088)
			(stroke
				(width 0.1)
				(type default)
			)
			(layer "F.Fab")
		)
		(fp_rect
			(start 0.850138 0.450088)
			(end 0.342138 -0.450088)
			(stroke
				(width 0)
				(type default)
			)
			(fill yes)
			(layer "F.Fab")
		)
		(fp_text user "A"
			(at -1.846326 -0.778002 0)
			(unlocked yes)
			(layer "F.SilkS")
			(effects
				(font
					(size 0.635 0.4064)
					(thickness 0.1524)
				)
			)
		)
		(fp_text user "C"
			(at 1.201674 -1.540002 0)
			(unlocked yes)
			(layer "F.SilkS")
			(effects
				(font
					(size 0.635 0.4064)
					(thickness 0.1524)
				)
			)
		)
		(fp_text user "A"
			(at -1.700276 0.032004 0)
			(unlocked yes)
			(layer "F.Fab")
			(effects
				(font
					(size 0.7874 0.5842)
					(thickness 0.1524)
				)
			)
		)
		(fp_text user "C"
			(at 0.828294 -1.159002 0)
			(unlocked yes)
			(layer "F.Fab")
			(effects
				(font
					(size 0.7874 0.5842)
					(thickness 0.1524)
				)
			)
		)
		(pad "A" smd rect
			(at -0.749808 0 270)
			(size 0.7874 0.7874)
			(layers "F.Cu" "F.Mask" "F.Paste")
			(net "UNNAMED_14_OPTICAL_I137_A")
		)
		(pad "C" smd rect
			(at 0.749808 0 270)
			(size 0.7874 0.7874)
			(layers "F.Cu" "F.Mask" "F.Paste")
			(net "LED_DATOUT0")
		)
	)
	(footprint ""
		(layer "F.Cu")
		(at 56.3372 -74.9808 90)
		(property "Reference" "C306"
			(at -0.5588 4.15417 90)
			(unlocked yes)
			(layer "F.SilkS")
			(effects
				(font
					(size 0.7874 0.5842)
					(thickness 0.1524)
				)
			)
		)
		(property "Value" "VAL*"
			(at 0.0762 2.067306 90)
			(unlocked yes)
			(layer "F.Fab")
			(hide yes)
			(effects
				(font
					(size 0.7874 0.5842)
					(thickness 0.1524)
				)
			)
		)
		(property "Tolerance" "TOL*"
			(at 0.0762 3.032506 90)
			(unlocked yes)
			(layer "Cmts.User")
			(hide yes)
			(effects
				(font
					(size 0.7874 0.5842)
					(thickness 0.1524)
				)
			)
		)
		(property "User Part Number" "PARTNUM*"
			(at 0.1016 4.023106 90)
			(unlocked yes)
			(layer "Cmts.User")
			(hide yes)
			(effects
				(font
					(size 0.7874 0.5842)
					(thickness 0.1524)
				)
			)
		)
		(property "Device Type" "CAPACITOR-G105-0B104-EK,0.1UF,A"
			(at 0.0508 1.127506 90)
			(unlocked yes)
			(layer "F.Fab")
			(hide yes)
			(effects
				(font
					(size 0.7874 0.5842)
					(thickness 0.1524)
				)
			)
		)
		(duplicate_pad_numbers_are_jumpers no)
		(fp_line
			(start 1.143 -0.5588)
			(end -1.143 -0.5588)
			(stroke
				(width 0.1)
				(type default)
			)
			(layer "F.SilkS")
		)
		(fp_line
			(start -1.143 -0.5588)
			(end -1.143 0.5588)
			(stroke
				(width 0.1)
				(type default)
			)
			(layer "F.SilkS")
		)
		(fp_line
			(start 1.143 0.5588)
			(end 1.143 -0.5588)
			(stroke
				(width 0.1)
				(type default)
			)
			(layer "F.SilkS")
		)
		(fp_line
			(start -1.143 0.5588)
			(end 1.143 0.5588)
			(stroke
				(width 0.1)
				(type default)
			)
			(layer "F.SilkS")
		)
		(fp_rect
			(start -1.143 0.5588)
			(end 1.143 -0.5588)
			(stroke
				(width 0)
				(type default)
			)
			(fill no)
			(layer "F.CrtYd")
		)
		(fp_line
			(start 0.508 -0.3048)
			(end -0.508 -0.3048)
			(stroke
				(width 0.1)
				(type default)
			)
			(layer "F.Fab")
		)
		(fp_line
			(start -0.508 -0.3048)
			(end -0.508 0.3048)
			(stroke
				(width 0.1)
				(type default)
			)
			(layer "F.Fab")
		)
		(fp_line
			(start 0.508 0.3048)
			(end 0.508 -0.3048)
			(stroke
				(width 0.1)
				(type default)
			)
			(layer "F.Fab")
		)
		(fp_line
			(start -0.508 0.3048)
			(end 0.508 0.3048)
			(stroke
				(width 0.1)
				(type default)
			)
			(layer "F.Fab")
		)
		(pad "1" smd rect
			(at -0.5334 0 90)
			(size 0.7112 0.6096)
			(layers "F.Cu" "F.Mask" "F.Paste")
			(net "SG")
		)
		(pad "2" smd rect
			(at 0.5334 0 90)
			(size 0.7112 0.6096)
			(layers "F.Cu" "F.Mask" "F.Paste")
			(net "XP3R3V_FPGA")
		)
		(zone
			(layer "F.Cu")
			(hatch none 0.5)
			(connect_pads
				(clearance 0)
			)
			(min_thickness 0.25)
			(keepout
				(tracks allowed)
				(vias not_allowed)
				(pads allowed)
				(copperpour not_allowed)
				(footprints allowed)
			)
			(placement
				(enabled no)
				(sheetname "")
			)
			(fill
				(thermal_gap 0.5)
				(thermal_bridge_width 0.5)
				(island_removal_mode 0)
			)
			(polygon
				(pts
					(xy 56.642 -74.9046) (xy 56.642 -75.057) (xy 56.0324 -75.057) (xy 56.0324 -74.9046)
				)
			)
		)
		(zone
			(layer "F.Cu")
			(hatch none 0.5)
			(connect_pads
				(clearance 0)
			)
			(min_thickness 0.25)
			(keepout
				(tracks not_allowed)
				(vias allowed)
				(pads allowed)
				(copperpour not_allowed)
				(footprints allowed)
			)
			(placement
				(enabled no)
				(sheetname "")
			)
			(fill
				(thermal_gap 0.5)
				(thermal_bridge_width 0.5)
				(island_removal_mode 0)
			)
			(polygon
				(pts
					(xy 56.642 -74.9046) (xy 56.642 -75.057) (xy 56.0324 -75.057) (xy 56.0324 -74.9046)
				)
			)
		)
	)
	(footprint ""
		(layer "F.Cu")
		(at 111.506 -69.088 -90)
		(property "Reference" "C233"
			(at 0.254 -3.34137 90)
			(unlocked yes)
			(layer "F.SilkS")
			(effects
				(font
					(size 0.7874 0.5842)
					(thickness 0.1524)
				)
			)
		)
		(property "Value" "VAL*"
			(at 0.0762 2.067306 270)
			(unlocked yes)
			(layer "F.Fab")
			(hide yes)
			(effects
				(font
					(size 0.7874 0.5842)
					(thickness 0.1524)
				)
			)
		)
		(property "Tolerance" "TOL*"
			(at 0.0762 3.032506 270)
			(unlocked yes)
			(layer "Cmts.User")
			(hide yes)
			(effects
				(font
					(size 0.7874 0.5842)
					(thickness 0.1524)
				)
			)
		)
		(property "User Part Number" "PARTNUM*"
			(at 0.1016 4.023106 270)
			(unlocked yes)
			(layer "Cmts.User")
			(hide yes)
			(effects
				(font
					(size 0.7874 0.5842)
					(thickness 0.1524)
				)
			)
		)
		(property "Device Type" "CAPACITOR-G105-0B104-CK,0.1UF,A"
			(at 0.0508 1.127506 270)
			(unlocked yes)
			(layer "F.Fab")
			(hide yes)
			(effects
				(font
					(size 0.7874 0.5842)
					(thickness 0.1524)
				)
			)
		)
		(duplicate_pad_numbers_are_jumpers no)
		(fp_line
			(start -1.143 0.5588)
			(end 1.143 0.5588)
			(stroke
				(width 0.1)
				(type default)
			)
			(layer "F.SilkS")
		)
		(fp_line
			(start 1.143 0.5588)
			(end 1.143 -0.5588)
			(stroke
				(width 0.1)
				(type default)
			)
			(layer "F.SilkS")
		)
		(fp_line
			(start -1.143 -0.5588)
			(end -1.143 0.5588)
			(stroke
				(width 0.1)
				(type default)
			)
			(layer "F.SilkS")
		)
		(fp_line
			(start 1.143 -0.5588)
			(end -1.143 -0.5588)
			(stroke
				(width 0.1)
				(type default)
			)
			(layer "F.SilkS")
		)
		(fp_rect
			(start 1.143 -0.5588)
			(end -1.143 0.5588)
			(stroke
				(width 0)
				(type default)
			)
			(fill no)
			(layer "F.CrtYd")
		)
		(fp_line
			(start -0.508 0.3048)
			(end 0.508 0.3048)
			(stroke
				(width 0.1)
				(type default)
			)
			(layer "F.Fab")
		)
		(fp_line
			(start 0.508 0.3048)
			(end 0.508 -0.3048)
			(stroke
				(width 0.1)
				(type default)
			)
			(layer "F.Fab")
		)
		(fp_line
			(start -0.508 -0.3048)
			(end -0.508 0.3048)
			(stroke
				(width 0.1)
				(type default)
			)
			(layer "F.Fab")
		)
		(fp_line
			(start 0.508 -0.3048)
			(end -0.508 -0.3048)
			(stroke
				(width 0.1)
				(type default)
			)
			(layer "F.Fab")
		)
		(pad "1" smd rect
			(at -0.5334 0 270)
			(size 0.7112 0.6096)
			(layers "F.Cu" "F.Mask" "F.Paste")
			(net "XP3R3V")
		)
		(pad "2" smd rect
			(at 0.5334 0 270)
			(size 0.7112 0.6096)
			(layers "F.Cu" "F.Mask" "F.Paste")
			(net "SG")
		)
		(zone
			(layer "F.Cu")
			(hatch none 0.5)
			(connect_pads
				(clearance 0)
			)
			(min_thickness 0.25)
			(keepout
				(tracks allowed)
				(vias not_allowed)
				(pads allowed)
				(copperpour not_allowed)
				(footprints allowed)
			)
			(placement
				(enabled no)
				(sheetname "")
			)
			(fill
				(thermal_gap 0.5)
				(thermal_bridge_width 0.5)
				(island_removal_mode 0)
			)
			(polygon
				(pts
					(xy 111.8108 -69.0118) (xy 111.8108 -69.1642) (xy 111.2012 -69.1642) (xy 111.2012 -69.0118)
				)
			)
		)
	)
	(footprint ""
		(layer "F.Cu")
		(at 8.4328 -68.201032 90)
		(property "Reference" "R393"
			(at 3.553968 -0.51943 90)
			(unlocked yes)
			(layer "F.SilkS")
			(effects
				(font
					(size 0.7874 0.5842)
					(thickness 0.1524)
				)
			)
		)
		(property "Value" "VAL*"
			(at 0.02032 2.13233 90)
			(unlocked yes)
			(layer "F.Fab")
			(hide yes)
			(effects
				(font
					(size 0.7874 0.5842)
					(thickness 0.1524)
				)
			)
		)
		(property "Tolerance" "TOL*"
			(at 0.044704 3.05435 90)
			(unlocked yes)
			(layer "Cmts.User")
			(hide yes)
			(effects
				(font
					(size 0.7874 0.5842)
					(thickness 0.1524)
				)
			)
		)
		(property "User Part Number" "PARTNUM*"
			(at 0.02032 4.024884 90)
			(unlocked yes)
			(layer "Cmts.User")
			(hide yes)
			(effects
				(font
					(size 0.7874 0.5842)
					(thickness 0.1524)
				)
			)
		)
		(property "Device Type" "RESISTOR-G155-133R0-01,33OHM,1%"
			(at 0.008382 1.210564 90)
			(unlocked yes)
			(layer "F.Fab")
			(hide yes)
			(effects
				(font
					(size 0.7874 0.5842)
					(thickness 0.1524)
				)
			)
		)
		(duplicate_pad_numbers_are_jumpers no)
		(fp_line
			(start 1.143 -0.5588)
			(end -1.143 -0.5588)
			(stroke
				(width 0.1)
				(type default)
			)
			(layer "F.SilkS")
		)
		(fp_line
			(start -1.143 -0.5588)
			(end -1.143 0.5588)
			(stroke
				(width 0.1)
				(type default)
			)
			(layer "F.SilkS")
		)
		(fp_line
			(start 1.143 0.5588)
			(end 1.143 -0.5588)
			(stroke
				(width 0.1)
				(type default)
			)
			(layer "F.SilkS")
		)
		(fp_line
			(start -1.143 0.5588)
			(end 1.143 0.5588)
			(stroke
				(width 0.1)
				(type default)
			)
			(layer "F.SilkS")
		)
		(fp_rect
			(start -1.143 -0.5588)
			(end 1.143 0.5588)
			(stroke
				(width 0)
				(type default)
			)
			(fill no)
			(layer "F.CrtYd")
		)
		(fp_line
			(start 0.508 -0.3048)
			(end -0.508 -0.3048)
			(stroke
				(width 0.1)
				(type default)
			)
			(layer "F.Fab")
		)
		(fp_line
			(start -0.508 -0.3048)
			(end -0.508 0.3048)
			(stroke
				(width 0.1)
				(type default)
			)
			(layer "F.Fab")
		)
		(fp_line
			(start 0.508 0.3048)
			(end 0.508 -0.3048)
			(stroke
				(width 0.1)
				(type default)
			)
			(layer "F.Fab")
		)
		(fp_line
			(start -0.508 0.3048)
			(end 0.508 0.3048)
			(stroke
				(width 0.1)
				(type default)
			)
			(layer "F.Fab")
		)
		(pad "1" smd rect
			(at -0.5334 0 90)
			(size 0.7112 0.6096)
			(layers "F.Cu" "F.Mask" "F.Paste")
			(net "SMA3_LED_RED_N")
		)
		(pad "2" smd rect
			(at 0.5334 0 90)
			(size 0.7112 0.6096)
			(layers "F.Cu" "F.Mask" "F.Paste")
			(net "UNNAMED_14_LED4PV14_I267_3")
		)
		(zone
			(layer "F.Cu")
			(hatch none 0.5)
			(connect_pads
				(clearance 0)
			)
			(min_thickness 0.25)
			(keepout
				(tracks not_allowed)
				(vias allowed)
				(pads allowed)
				(copperpour not_allowed)
				(footprints allowed)
			)
			(placement
				(enabled no)
				(sheetname "")
			)
			(fill
				(thermal_gap 0.5)
				(thermal_bridge_width 0.5)
				(island_removal_mode 0)
			)
			(polygon
				(pts
					(xy 8.128 -68.124832) (xy 8.7376 -68.124832) (xy 8.7376 -68.277232) (xy 8.128 -68.277232)
				)
			)
		)
		(zone
			(layer "F.Cu")
			(hatch none 0.5)
			(connect_pads
				(clearance 0)
			)
			(min_thickness 0.25)
			(keepout
				(tracks allowed)
				(vias not_allowed)
				(pads allowed)
				(copperpour not_allowed)
				(footprints allowed)
			)
			(placement
				(enabled no)
				(sheetname "")
			)
			(fill
				(thermal_gap 0.5)
				(thermal_bridge_width 0.5)
				(island_removal_mode 0)
			)
			(polygon
				(pts
					(xy 8.128 -68.124832) (xy 8.7376 -68.124832) (xy 8.7376 -68.277232) (xy 8.128 -68.277232)
				)
			)
		)
	)
	(footprint ""
		(layer "F.Cu")
		(at 87.503 -67.31)
		(property "Reference" "TP19"
			(at -0.7874 -0.85725 0)
			(unlocked yes)
			(layer "F.SilkS")
			(effects
				(font
					(size 0.635 0.4064)
					(thickness 0.1524)
				)
				(justify left)
			)
		)
		(property "Value" ""
			(at 0 0 0)
			(layer "F.Fab")
			(effects
				(font
					(size 1.27 1.27)
				)
			)
		)
		(property "Device Type" "TP_PIONT-TP010CT020B030_PTH-TPA"
			(at -1.341882 0.996696 0)
			(unlocked yes)
			(layer "F.Fab")
			(hide yes)
			(effects
				(font
					(size 0.7874 0.5842)
					(thickness 0.000001)
				)
				(justify left)
			)
		)
		(duplicate_pad_numbers_are_jumpers no)
		(fp_poly
			(pts
				(arc
					(start 0.889 0)
					(mid -0.889 0)
					(end 0.889 0)
				)
			)
			(stroke
				(width 0)
				(type default)
			)
			(fill no)
			(layer "B.CrtYd")
		)
		(fp_poly
			(pts
				(arc
					(start 0.889 0)
					(mid -0.889 0)
					(end 0.889 0)
				)
			)
			(stroke
				(width 0)
				(type default)
			)
			(fill no)
			(layer "F.CrtYd")
		)
		(pad "1" thru_hole circle
			(at 0 0)
			(size 0.508 0.508)
			(drill 0.254)
			(layers "*.Cu" "*.Mask")
			(remove_unused_layers no)
			(net "SN_EEPROM_WP")
			(clearance 0.1016)
			(padstack
				(mode front_inner_back)
				(layer "Inner"
					(shape circle)
					(size 0.508 0.508)
					(clearance 0.1016)
				)
				(layer "B.Cu"
					(shape circle)
					(size 0.762 0.762)
					(clearance -0.0254)
				)
			)
		)
	)
)
